# BASEBOARD_FAB2 (Tioga Pass) — schematic netlist excerpt (pin names and nets, part order shuffled) for the footprints in the layout excerpt that follows; sources: Cadence DE-HDL packaged netlist, KiCad conversion of Wiwynn_Tioga_Pass_MB.brd

C7G3  CAP  220PF 50V 10% X7R  pkg 0402LF  page 215 : A = A_TSENSE_PVDDQ_ABC ; B = GND
CR10W3  DIODE  SDMK0340L IC  pkg SM  page 251 : C = PUMP_TACH1_D ; A = PUMP_TACH1_R
C5D49  CAP_A  22.0UF 4V 20% X6S  pkg 0603V  page 42 : A = PVCCMCP_CPU0 ; B = GND

(kicad_pcb
	(version 20260206)
	(generator "pcbnew")
	(generator_version "10.0")
	(general
		(thickness 1.6)
		(legacy_teardrops no)
	)
	(paper "A4")
	(title_block
		(title "Wiwynn_Tioga_Pass_MB.brd")
		(comment 1 "Tioga Pass / footprints 2154-2156 of 4770")
	)
	(layers
		(0 "F.Cu" signal "TOP")
		(4 "In1.Cu" signal "L2GND")
		(6 "In2.Cu" signal "L3")
		(8 "In3.Cu" signal "L4GND")
		(10 "In4.Cu" signal "L5")
		(12 "In5.Cu" signal "L6GND")
		(14 "In6.Cu" signal "L7VCC")
		(16 "In7.Cu" signal "L8VCC")
		(18 "In8.Cu" signal "L9GND")
		(20 "In9.Cu" signal "L10")
		(22 "In10.Cu" signal "L11GND")
		(24 "In11.Cu" signal "L12")
		(26 "In12.Cu" signal "L13GND")
		(2 "B.Cu" signal "BOTTOM")
		(9 "F.Adhes" user "F.Adhesive")
		(11 "B.Adhes" user "B.Adhesive")
		(13 "F.Paste" user "Package Geometry/Pastemask Top")
		(15 "B.Paste" user "Package Geometry/Pastemask Bottom")
		(5 "F.SilkS" user "Ref Des/Silkscreen Top")
		(7 "B.SilkS" user "Ref Des/Silkscreen Bottom")
		(1 "F.Mask" user "Board Geometry/Soldermask Top")
		(3 "B.Mask" user "Board Geometry/Soldermask Bottom")
		(17 "Dwgs.User" user "User.Drawings")
		(19 "Cmts.User" user "User.Comments")
		(21 "Eco1.User" user "User.Eco1")
		(23 "Eco2.User" user "User.Eco2")
		(25 "Edge.Cuts" user "Board Geometry/Outline")
		(27 "Margin" user)
		(31 "F.CrtYd" user "Package Geometry/Place Bound Top")
		(29 "B.CrtYd" user "Package Geometry/Place Bound Bottom")
		(35 "F.Fab" user "Ref Des/Assembly Top")
		(33 "B.Fab" user "Ref Des/Assembly Bottom")
	)
	(footprint ""
		(layer "F.Cu")
		(at 274.438872 -73.318116)
		(property "Reference" "C5D49"
			(at 0 0 0)
			(layer "F.SilkS")
			(hide yes)
			(effects
				(font
					(size 1.27 1.27)
				)
			)
		)
		(property "Value" ""
			(at 0 0 0)
			(layer "F.Fab")
			(effects
				(font
					(size 1.27 1.27)
				)
			)
		)
		(duplicate_pad_numbers_are_jumpers no)
		(fp_poly
			(pts
				(xy -0.4953 -0.2032) (xy 0.4953 -0.2032) (xy 0.4953 1.6002) (xy -0.4953 1.6002)
			)
			(stroke
				(width 0)
				(type default)
			)
			(fill no)
			(layer "F.CrtYd")
		)
		(fp_line
			(start -0.4953 -0.2032)
			(end 0.4953 -0.2032)
			(stroke
				(width 0.1)
				(type default)
			)
			(layer "F.Fab")
		)
		(fp_line
			(start -0.4953 1.6002)
			(end -0.4953 -0.2032)
			(stroke
				(width 0.1)
				(type default)
			)
			(layer "F.Fab")
		)
		(fp_line
			(start 0.4953 -0.2032)
			(end 0.4953 1.6002)
			(stroke
				(width 0.1)
				(type default)
			)
			(layer "F.Fab")
		)
		(fp_line
			(start 0.4953 1.6002)
			(end -0.4953 1.6002)
			(stroke
				(width 0.1)
				(type default)
			)
			(layer "F.Fab")
		)
		(pad "1" smd rect
			(at 0 0)
			(size 0.762 0.889)
			(layers "F.Cu" "F.Mask" "F.Paste")
			(net "PVCCMCP_CPU0")
		)
		(pad "2" smd rect
			(at 0 1.397)
			(size 0.762 0.889)
			(layers "F.Cu" "F.Mask" "F.Paste")
			(net "GND")
		)
		(zone
			(layer "F.Cu")
			(hatch none 0.5)
			(connect_pads
				(clearance 0)
			)
			(min_thickness 0.25)
			(keepout
				(tracks not_allowed)
				(vias allowed)
				(pads allowed)
				(copperpour not_allowed)
				(footprints allowed)
			)
			(placement
				(enabled no)
				(sheetname "")
			)
			(fill
				(thermal_gap 0.5)
				(thermal_bridge_width 0.5)
				(island_removal_mode 0)
			)
			(polygon
				(pts
					(xy 274.057872 -72.873616) (xy 274.819872 -72.873616) (xy 274.819872 -72.365616) (xy 274.057872 -72.365616)
				)
			)
		)
	)
	(footprint ""
		(layer "F.Cu")
		(at -3.739388 -114.954812 90)
		(property "Reference" "CR10W3"
			(at 1.06934 -0.39116 0)
			(unlocked yes)
			(layer "F.SilkS")
			(effects
				(font
					(size 0.4064 0.254)
					(thickness 0.1524)
				)
				(justify left)
			)
		)
		(property "Value" ""
			(at 0 0 90)
			(layer "F.Fab")
			(effects
				(font
					(size 1.27 1.27)
				)
			)
		)
		(duplicate_pad_numbers_are_jumpers no)
		(fp_line
			(start 0.819404 -0.070866)
			(end 0.819404 1.052576)
			(stroke
				(width 0.1524)
				(type default)
			)
			(layer "F.SilkS")
		)
		(fp_line
			(start 1.300226 1.052576)
			(end 0.338582 1.052576)
			(stroke
				(width 0.1524)
				(type default)
			)
			(layer "F.SilkS")
		)
		(fp_line
			(start 0.819404 1.052576)
			(end 1.300226 1.885442)
			(stroke
				(width 0.1524)
				(type default)
			)
			(layer "F.SilkS")
		)
		(fp_line
			(start 1.300226 1.885442)
			(end 0.819404 1.885442)
			(stroke
				(width 0.1524)
				(type default)
			)
			(layer "F.SilkS")
		)
		(fp_line
			(start 0.819404 1.885442)
			(end 0.338582 1.885442)
			(stroke
				(width 0.1524)
				(type default)
			)
			(layer "F.SilkS")
		)
		(fp_line
			(start 0.338582 1.885442)
			(end 0.819404 1.052576)
			(stroke
				(width 0.1524)
				(type default)
			)
			(layer "F.SilkS")
		)
		(fp_line
			(start 0.819404 2.797048)
			(end 0.819404 1.885442)
			(stroke
				(width 0.1524)
				(type default)
			)
			(layer "F.SilkS")
		)
		(fp_poly
			(pts
				(xy -0.67437 0.24384) (xy -0.67437 2.04216) (xy 0.67437 2.04216) (xy 0.67437 0.24384)
			)
			(stroke
				(width 0)
				(type default)
			)
			(fill no)
			(layer "F.CrtYd")
		)
		(fp_line
			(start 0.67437 0.24384)
			(end -0.67437 0.24384)
			(stroke
				(width 0.1)
				(type default)
			)
			(layer "F.Fab")
		)
		(fp_line
			(start -0.67437 0.24384)
			(end -0.67437 2.04216)
			(stroke
				(width 0.1)
				(type default)
			)
			(layer "F.Fab")
		)
		(fp_line
			(start -0.854456 0.831596)
			(end -1.8161 0.831596)
			(stroke
				(width 0.1)
				(type default)
			)
			(layer "F.Fab")
		)
		(fp_line
			(start -1.335278 0.831596)
			(end -1.335278 -0.291846)
			(stroke
				(width 0.1)
				(type default)
			)
			(layer "F.Fab")
		)
		(fp_line
			(start -1.335278 0.831596)
			(end -0.854456 1.664462)
			(stroke
				(width 0.1)
				(type default)
			)
			(layer "F.Fab")
		)
		(fp_line
			(start -0.854456 1.664462)
			(end -1.8161 1.664462)
			(stroke
				(width 0.1)
				(type default)
			)
			(layer "F.Fab")
		)
		(fp_line
			(start -1.335278 1.664462)
			(end -1.335278 2.576068)
			(stroke
				(width 0.1)
				(type default)
			)
			(layer "F.Fab")
		)
		(fp_line
			(start -1.8161 1.664462)
			(end -1.335278 0.831596)
			(stroke
				(width 0.1)
				(type default)
			)
			(layer "F.Fab")
		)
		(fp_line
			(start 0.67437 2.04216)
			(end 0.67437 0.24384)
			(stroke
				(width 0.1)
				(type default)
			)
			(layer "F.Fab")
		)
		(fp_line
			(start -0.67437 2.04216)
			(end 0.67437 2.04216)
			(stroke
				(width 0.1)
				(type default)
			)
			(layer "F.Fab")
		)
		(pad "1" smd rect
			(at 0 0 90)
			(size 0.4064 1.016)
			(layers "F.Cu" "F.Mask" "F.Paste")
			(net "PUMP_TACH1_D")
		)
		(pad "2" smd rect
			(at 0 2.286 90)
			(size 0.4064 1.016)
			(layers "F.Cu" "F.Mask" "F.Paste")
			(net "PUMP_TACH1_R")
		)
	)
	(footprint ""
		(layer "F.Cu")
		(at 349.123 -13.843 90)
		(property "Reference" "C7G3"
			(at 0 0 90)
			(layer "F.SilkS")
			(hide yes)
			(effects
				(font
					(size 1.27 1.27)
				)
			)
		)
		(property "Value" ""
			(at 0 0 90)
			(layer "F.Fab")
			(effects
				(font
					(size 1.27 1.27)
				)
			)
		)
		(duplicate_pad_numbers_are_jumpers no)
		(fp_rect
			(start -0.3048 -0.1016)
			(end 0.3048 0.9906)
			(stroke
				(width 0)
				(type default)
			)
			(fill no)
			(layer "F.CrtYd")
		)
		(fp_line
			(start 0.3048 -0.1016)
			(end -0.3048 -0.1016)
			(stroke
				(width 0.1)
				(type default)
			)
			(layer "F.Fab")
		)
		(fp_line
			(start -0.3048 -0.1016)
			(end -0.3048 0.9906)
			(stroke
				(width 0.1)
				(type default)
			)
			(layer "F.Fab")
		)
		(fp_line
			(start 0.3048 0.9906)
			(end 0.3048 -0.1016)
			(stroke
				(width 0.1)
				(type default)
			)
			(layer "F.Fab")
		)
		(fp_line
			(start -0.3048 0.9906)
			(end 0.3048 0.9906)
			(stroke
				(width 0.1)
				(type default)
			)
			(layer "F.Fab")
		)
		(pad "1" smd rect
			(at 0 0 90)
			(size 0.508 0.508)
			(layers "F.Cu" "F.Mask" "F.Paste")
			(net "A_TSENSE_PVDDQ_ABC")
		)
		(pad "2" smd rect
			(at 0 0.889 90)
			(size 0.508 0.508)
			(layers "F.Cu" "F.Mask" "F.Paste")
			(net "GND")
		)
		(zone
			(layer "F.Cu")
			(hatch none 0.5)
			(connect_pads
				(clearance 0)
			)
			(min_thickness 0.25)
			(keepout
				(tracks not_allowed)
				(vias allowed)
				(pads allowed)
				(copperpour not_allowed)
				(footprints allowed)
			)
			(placement
				(enabled no)
				(sheetname "")
			)
			(fill
				(thermal_gap 0.5)
				(thermal_bridge_width 0.5)
				(island_removal_mode 0)
			)
			(polygon
				(pts
					(xy 349.377 -13.589) (xy 349.758 -13.589) (xy 349.758 -14.097) (xy 349.377 -14.097)
				)
			)
		)
		(zone
			(layer "F.Cu")
			(hatch none 0.5)
			(connect_pads
				(clearance 0)
			)
			(min_thickness 0.25)
			(keepout
				(tracks allowed)
				(vias not_allowed)
				(pads allowed)
				(copperpour not_allowed)
				(footprints allowed)
			)
			(placement
				(enabled no)
				(sheetname "")
			)
			(fill
				(thermal_gap 0.5)
				(thermal_bridge_width 0.5)
				(island_removal_mode 0)
			)
			(polygon
				(pts
					(xy 349.377 -13.589) (xy 349.758 -13.589) (xy 349.758 -14.097) (xy 349.377 -14.097)
				)
			)
		)
	)
)
